                    - SPARES  LIST -

MOSFET_NCH_DUAL-PJT138K,SMLF,IC,BAM138K0003
    Q6000  2

                    - PART SUMMARY -

74CBTLV3126PW-74CBTLV3126PW,SMLF,IC,AL003126K08	AL003126K08	4
74LV4052PW-74LV4052PW,SMLF,IC,ALLV4052K19	ALLV4052K19	2
74LVC1G07GV-74LVC1G07GV,SMLF,IC,AL1G0007001	AL1G0007001	4
74LVC1G08W57-74LVC1G08W5-7,SMLF,IC,AL1G0008020	AL1G0008020	7
74LVC1G126SE7-74LVC1G126SE-7,SMLF,IC,AL1G0126009	AL1G0126009	8
74LVC1G17GW-74LVC1G17GW,SMLF,IC,AL1G0017K01	AL1G0017K01	3
74LVC1G32GW_SMLF-74LVC1G32GW,IC,ALVC1G32007	ALVC1G32007	3
74LVC1G66GV-74LVC1G66GV,SMLF,IC,AL001G66000	AL001G66000	2
74LVC2G07DW7-74LVC2G07DW-7,SMLF,EMPTY,AL002G07003	AL002G07003	1
74LVC2G07DW7-74LVC2G07DW-7,SMLF,IC,AL002G07003	AL002G07003	8
74LVC2G08DP-74LVC2G08DP,SMLF,EMPTY,ALVC2G08K01	ALVC2G08K01	3
74LVC2G17GW-74LVC2G17GW,SMLF,IC,AL2G0017005	AL2G0017005	6
9FGL0251DKILFT-9FGL0251DKILFT,SMLF,IC,AL000251002	AL000251002	1
9ZXL0451EKILFT-9ZXL0451EKILFT,SMLF,IC,AL000451003	AL000451003	2
ADC128D818CIMTXNOPB-ADC128D818CIMTX/NOPB,SMLF,IC,AA	AL000128K00	2
AP331AWG7-AP331AWG-7,SMLF,EMPTY,AL000331011	AL000331011	1
AP331AWG7-AP331AWG-7,SMLF,IC,AL000331011	AL000331011	2
APX80929SAG7-APX809-29SAG-7,SMLF,IC,AL080929000	AL080929000	4
BAT547F-BAT547F,SMLF,IC,BC0BAT54Z53	BC0BAT54Z53	1
BSS138DW7F-BSS138DW-7-F,SMLF,IC,BAM01380032	BAM01380032	3
CONN10_HBC1051L300D8H-CONN10_HBC1051-L300D-8H,THLFA	DFHD10MS117	1
CONN112_10137002101LF-CONN112_10137002-101LF,THLF,A	DFHSB2FR012	7
CONN160_10131762101LF-CONN160_10131762-101LF,THLF,A	DFHSG0FR007	1
CONN1_10165288101LF-CONN1_10165288-101LF,THLF,IO,DA	DFHS03FR030	2
CONN2_AAABAT029Y19-CONN2_AAA-BAT-029-Y19,THLF,IO,DA	DFHS02FR062	1
CONN3_210HP1030BR1-CONN3_210-HP1-030BR1,THLF,IO,DFA	DFHD03MS213	7
CONN4_HFK1040L0P1L7H-CONN4_HFK1040-L0P1L-7H,THLF,IA	DFHD04MS460	2
CONN60_101062636003K02LF-CONN60_10106263-6003K02LFA	DFHD60MR024	1
CONN6_HBC1031L200D8H-CONN6_HBC1031-L200D-8H,THLF,IA	DFHD06MS263	1
CONN8_HBB1081L200D8H-CONN8_HBB1081-L200D-8H,THLF,IA	DFHD08MS197	1
CYUSB330468LTXI-CYUSB3304-68LTXI,SMLF,IC,AJ0330400A	AJ033040001	1
DIODE_TVS-SMF14A,SMLF,IC,BCSMF14AZ01	BCSMF14AZ01	4
DS125BR111RTWR-DS125BR111RTWR,SMLF,IC,AL000125003	AL000125003	1
GENOA_SP5-SOCKET6096_13568-001,SMLF,IO,DGA^6000030	DGA^6000030	2
GL852GOHY60-GL852G-OHY60,SMLF,IC,AL000852001	AL000852001	1
GND_HOLE_TH-EMPTY,GND_HOLE140	GND_HOLE140	2
GND_HOLE_TH-EMPTY,GND_HOLE514	GND_HOLE514	1
GND_HOLE_TH-EMPTY,TMP-QGND_HOLE12	TMP-QGND_HOLE12	2
HOLE_TH-EMPTY,DUMMY50	DUMMY50	4
HOLE_TH-EMPTY,HOLE1187	HOLE1187	2
HOLE_TH-EMPTY,HOLE1195	HOLE1195	1
HOLE_TH-EMPTY,HOLE1226	HOLE1226	24
HOLE_TH-EMPTY,HOLE1247	HOLE1247	2
HOLE_TH-EMPTY,HOLE1248	HOLE1248	2
HOLE_TH-EMPTY,HOLE372	HOLE372	1
HOLE_TH-EMPTY,HOLE596	HOLE596	21
HOLE_TH-EMPTY,TMP-C_T2I_ALEX_1121_1	TMP-C_T2I_ALEX_1121_1	4
IML3112Y2B000NCG8-IML3112-Y2B000NCG8,SMLF,EMPTY,ALA	AL003112004	1
ISL28022FRZT-ISL28022FRZ-T,SMLF,IC,AL028022003	AL028022003	9
ISL69260IRAZT-ISL69260IRAZ-T,SMLF,IC,AL069260000	AL069260000	2
ISL99390FRZTR5935-ISL99390FRZ-TR5935,SMLF,IC,AL099A	AL099390004	46
LCMXO3LF9400C5BG484C-LCMXO3LF-9400C-5BG484C,SMLF,IA	AJ094000T08	1
LM4040AIM3X25NOPB-LM4040AIM3X-2.5/NOPB,SMLF,EMPTY,A	AL404025013	1
LM4040AIM3X25NOPB-LM4040AIM3X-2.5/NOPB,SMLF,IC,AL4A	AL404025013	2
LM75BD-LM75BD,SMLF,IC,AL0075BD000	AL0075BD000	4
LT6700CS61TRPBF-LT6700CS6-1#TRPBF,SMLF,EMPTY,AL006A	AL006700001	2
LTC4307CMS8-LTC4307CMS8,SMLF,EMPTY,AL004307000	AL004307000	1
LTC4307CMS8-LTC4307CMS8,SMLF,IC,AL004307000	AL004307000	4
M24128BWMN6TP-M24128-BWMN6TP,SMLF,IC,AKE30Z00613	AKE30Z00613	3
M24M02DRMN6TP-M24M02-DRMN6TP,SMLF,IC,AKE33Z00600	AKE33Z00600	8
MAX11617EEET-MAX11617EEE+T,SMLF,EMPTY,AL011617W00	AL011617W00	2
MAX15090BEWIT-MAX15090BEWI+T,SMLF,IC,AL015080B00	AL015080B00	7
METR3904G-METR3904-G,SMLF,IC,BA039040020	BA039040020	1
MOSFET_DUAL_6P-2N7002KDW,SMLF,IC,BAM70020047	BAM70020047	5
MOSFET_NCH_1D3S-PSMNR58-30YLH,SMLF,EMPTY,BAMNR5800A	BAMNR580000	2
MOSFET_NCH_1D3S-PSMNR58-30YLH,SMLF,IC,BAMNR580000	BAMNR580000	9
MOSFET_NCH_DUAL-PJT138K,SMLF,IC,BAM138K0003	BAM138K0003	57
MOSFET_NCH_GDS_ESD_PROTECTED-2N7002K,SMLF,EMPTY,BAA	BAM70020002	1
MOSFET_NCH_GDS_ESD_PROTECTED-2N7002K,SMLF,IC,BAM70A	BAM70020002	6
MOSFET_N_GSD-NX138BK,SMLF,IC,BAM01380023	BAM01380023	4
MOSFET_N_SMLF-BSS138K,BSS138K,EMPTY,BAM138K0000	BAM138K0000	1
MOSFET_N_SMLF-BSS138K,BSS138K,IC,BAM138K0000	BAM138K0000	9
MOSFET_PCH_GDS_ESD_PROTECTED-DMP2035U-7,SMLF,EMPTYA	BAM20350002	2
MOSFET_PCH_GDS_ESD_PROTECTED-PJA3415AE,SMLF,IC,BAMA	BAM34150008	4
MP5016GQHLZ-MP5016GQH-L-Z,SMLF,IC,AL005016007	AL005016007	3
MP5990GMA1111Z-MP5990GMA-1111-Z,SMLF,IC,AR0F0TP4023	AR0F0TP4023	1
MP5991GLUZ-MP5991GLU-Z,SMLF,IC,AL005991A00	AL005991A00	4
MPQ8626GDZ-MPQ8626GD-Z,SMLF,IC,AL008626000	AL008626000	2
MPQ8633AGLEC807Z-MPQ8633AGLE-C807-Z,SMLF,IC,AL0086A	AL008633007	2
MPQ8633BGLEC838Z-MPQ8633BGLE-C838-Z,SMLF,IC,AL0086A	AL008633005	4
NC7SB3157P6X-NC7SB3157P6X,SMLF,IC,ALSB3157000	ALSB3157000	1
NC7SB3157_SMLF-NC7SB3157P6X,NC7SB3157P6X,EMPTY,ALSA	ALSB3157000	4
NCP3284AMNTXG-NCP3284AMNTXG,SMLF,IC,AL003284002	AL003284002	1
NCP698SQ15T1G-NCP698SQ15T1G,SMLF,EMPTY,AL000698000	AL000698000	1
NCT7718W-NCT7718W,SMLF,IC,AL007718001	AL007718001	1
PCA9306DP1-PCA9306DP1,SMLF,IC,AL009306K04	AL009306K04	1
PCA9539RPW-PCA9539RPW,SMLF,IC,AL009539K07	AL009539K07	1
PCA9617ADP-PCA9617ADP,SMLF,EMPTY,AL009617K02	AL009617K02	1
PCA9617ADP-PCA9617ADP,SMLF,IC,AL009617K02	AL009617K02	6
PI3CSW12ZUAEX-PI3CSW12ZUAEX,SMLF,IC,AL3CSW12000	AL3CSW12000	14
PI3EQX12902AZLEX-PI3EQX12902AZLEX,SMLF,IC,AL012902A	AL012902001	1
PI4ULS3V304AZMAEX-PI4ULS3V304AZMAEX,SMLF,IC,AL0003A	AL000304005	1
PI6CV304LE-PI6CV304LE,SMLF,IC,AL000304K01	AL000304K01	1
PICOPROBE_BXA-DELTA-L 4.0,SMLF,EMPTY,TP33	TP33	32
PT5161LRS-PT5161LRS,SMLF,IC,AJ051610U03	AJ051610U03	8
Q_CAPP_SMLF-100UF,16V,20%,OSCON,CC71003MZ30	CC71003MZ30	4
Q_CAPP_SMLF-220UF,4V,20%,SPCAP,CH122KM8801	CH122KM8801	20
Q_CAPP_SMLF-220UF,6.3V,20%,ALUM,CC72201MZ28	CC72201MZ28	1
Q_CAPP_SMLF-270UF,16V,20%,OSCON,CC72703MZ11	CC72703MZ11	5
Q_CAPP_SMLF-390UF,2.5V,20%,ALUM,CC7390JMZ13	CC7390JMZ13	22
Q_CAPP_SMLF-470UF,2.5V,20%,EMPTY,CH747LM8825	CH747LM8825	4
Q_CAPP_SMLF-470UF,2.5V,20%,SPCAP,CH747LM8818	CH747LM8818	34
Q_CAPP_SMLF-470UF,2.5V,20%,SPCAP,CH747LM8825	CH747LM8825	14
Q_CAPP_THLF-270UF,16V,20%,OSCON,CC72703MD38	CC72703MD38	13
Q_CAPP_THLF-560UF,6.3V,20%,OSCON,CC75601MD16	CC75601MD16	2
Q_CAP_0201-1UF,4V,20%,X6S,CH-10KMEE00	CH-10KMEE00	136
Q_CAP_0402-0.022UF,25V,10%,X7R,CH3224K1B01	CH3224K1B01	2
Q_CAP_0402-0.068UF,16V,10%,X7R,CH3683K1B09	CH3683K1B09	8
Q_CAP_0402-0.1UF,25V,10%,EMPTY,CH4104K1B00	CH4104K1B00	24
Q_CAP_0402-0.1UF,25V,10%,X7R,CH4104K1B00	CH4104K1B00	472
Q_CAP_0402-0.22UF,16V,10%,X7R,CH4223K1B00	CH4223K1B00	50
Q_CAP_0402-1000PF,50V,5%,EMPTY,TMP_QCH21006JB10	CH21006JB10	17
Q_CAP_0402-1000PF,50V,5%,X7R,TMP_QCH21006JB10	CH21006JB10	33
Q_CAP_0402-100PF,50V,5%,EMPTY,CH11006JB18	CH11006JB18	16
Q_CAP_0402-100PF,50V,5%,NPO,CH11006JB00	CH11006JB00	3
Q_CAP_0402-100PF,50V,5%,X7R,CH11006JB18	CH11006JB18	3
Q_CAP_0402-10PF,50V,1%,NPO,TMP_QCH0106F0B00	CH0106F0B00	3
Q_CAP_0402-10PF,50V,5%,EMPTY,CH01006JB08	CH01006JB08	12
Q_CAP_0402-150PF,50V,5%,NPO,TMP_QCH11506JB08	CH11506JB08	2
Q_CAP_0402-15PF,50V,5%,C0G,CH01506JB06	CH01506JB06	3
Q_CAP_0402-1NF,50V,10%,EMPTY,CH21006KB16	CH21006KB16	5
Q_CAP_0402-1UF,6.3V,10%,X7R,CH5101K1B01	CH5101K1B01	4
Q_CAP_0402-220PF,50V,10%,EMPTY,TMP_QCH12206KB14	CH12206KB14	3
Q_CAP_0402-220PF,50V,10%,X7R,TMP_QCH12206KB14	CH12206KB14	3
Q_CAP_0402-27PF,50V,5%,NPO,CH02706JB06	CH02706JB06	2
Q_CAP_0402-3300PF,50V,10%,X7R,TMP_QCH2336K1B12	CH2336K1B12	18
Q_CAP_0402-330PF,50V,10%,X7R,CH1336K1B02	CH1336K1B02	2
Q_CAP_0402-33PF,50V,5%,NPO,TMP_QCH03306JB04	CH03306JB04	3
Q_CAP_0402-39PF,50V,5%,NPO,CH03906JB06	CH03906JB06	3
Q_CAP_0402-4.7UF,6.3V,20%,X6S,CH5471MEB01	CH5471MEB01	56
Q_CAP_0402-470PF,50V,10%,X7R,TMP_QCH14706KB18	CH14706KB18	13
Q_CAP_0402-47PF,50V,5%,NPO,TMP_QCH04706JB01	CH04706JB01	1
Q_CAP_0603-1000PF,50V,10%,X7R,TMP_QCH21006K917	CH21006K917	1
Q_CAP_0603-1UF,16V,10%,X7R,TMP_QCH5103K1900	CH5103K1900	1
Q_CAP_C0201-0.1UF,10V,10%,X7S,CH4102K6E00	CH4102K6E00	186
Q_CAP_C0402-0.001UF,50V,10%,EMPTY,CH30106KB19	CH30106KB19	12
Q_CAP_C0402-0.001UF,50V,10%,X7R,CH30106KB19	CH30106KB19	15
Q_CAP_C0402-0.01UF,25V,10%,EMPTY,CH3104K1B11	CH3104K1B11	2
Q_CAP_C0402-0.01UF,50V,10%,EMPTY,CH31006KB18	CH31006KB18	10
Q_CAP_C0402-0.01UF,50V,10%,X7R,CH31006KB18	CH31006KB18	32
Q_CAP_C0402-0.047UF,25V,10%,X7R,CH3474K1B04	CH3474K1B04	5
Q_CAP_C0402-0.1UF,16V,10%,X7R,CH4103K1B08	CH4103K1B08	45
Q_CAP_C0402-0.1UF,25V,10%,EMPTY,CH4104KEB00	CH4104KEB00	3
Q_CAP_C0402-0.1UF,25V,10%,X6S,CH4104KEB00	CH4104KEB00	6
Q_CAP_C0402-0.22UF,25V,10%,X7R,CH4224K1B01	CH4224K1B01	6
Q_CAP_C0402-100NF,50V,10%,EMPTY,CH4106K1B01	CH4106K1B01	7
Q_CAP_C0402-100NF,50V,10%,X7R,CH4106K1B01	CH4106K1B01	32
Q_CAP_C0402-10UF,6.3V,20%,EMPTY,CH6101MEB01	CH6101MEB01	1
Q_CAP_C0402-10UF,6.3V,20%,X6S,CH6101MEB01	CH6101MEB01	67
Q_CAP_C0402-10UF,6.3V,20%,X6S,CH6101MEB03	CH6101MEB03	8
Q_CAP_C0402-12PF,50V,5%,C0G,CH01206JB05	CH01206JB05	1
Q_CAP_C0402-1PF,50V,0.05P,COG,CH-106T0B00	CH-106T0B00	9
Q_CAP_C0402-1UF,16V,10%,X6S,CH5103KEB01	CH5103KEB01	11
Q_CAP_C0402-1UF,25V,10%,EMPTY,CH5104KEB02	CH5104KEB02	5
Q_CAP_C0402-1UF,25V,10%,X6S,CH5104KEB02	CH5104KEB02	115
Q_CAP_C0402-2.2UF,10V,10%,X6S,CH5222KEB01	CH5222KEB01	92
Q_CAP_C0402-2.7PF,50V,0.1PF,NPO,CH-276B0B00	CH-276B0B00	2
Q_CAP_C0402-220PF,50V,5%,C0G,CH12206JB00	CH12206JB00	4
Q_CAP_C0402-22UF,4V,20%,X6S,CH622KMEB02	CH622KMEB02	642
Q_CAP_C0402-3.9P,50V,0.1P,NPO,CH-3916TB01	CH-3916TB01	2
Q_CAP_C0402-33NF,25V,10%,EMPTY,CH3334K1B00	CH3334K1B00	1
Q_CAP_C0402-3900PF,50V,10%,X7R,CH23906KB14	CH23906KB14	4
Q_CAP_C0402-4.7PF,50V,0.1P,NPO,CH-4716TB06	CH-4716TB06	2
Q_CAP_C0402-560PF,50V,10%,EMPTY,CH1566K1B09	CH1566K1B09	46
Q_CAP_C0402-560PF,50V,10%,X7R,CH1566K1B09	CH1566K1B09	2
Q_CAP_C0402-6800PF,50V,10%,X7R,CH2686K1B01	CH2686K1B01	3
Q_CAP_C0402-8.2PF,50V,0.1P,NP0,CH-8216TB09	CH-8216TB09	2
Q_CAP_C0603-2.2UF,16V,10%,X6S,CH5223KE901	CH5223KE901	1
Q_CAP_C0603-2.2UF,16V,20%,X7R,CH5223M1900	CH5223M1900	4
Q_CAP_C0603-22UF,6.3V,20%,X6S,CH6221ME900	CH6221ME900	8
Q_CAP_C0603-4.7UF,16V,10%,X6S,CH5473KE902	CH5473KE902	1
Q_CAP_C0805-100UF,4V,20%,X6S,CH710KMEA01	CH710KMEA01	64
Q_CAP_C0805-10UF,16V,10%,EMPTY,CH6103KEA00	CH6103KEA00	2
Q_CAP_C0805-10UF,16V,10%,X6S,CH6103KEA00	CH6103KEA00	10
Q_CAP_C0805-10UF,16V,10%,X6S,CH6103KEA01	CH6103KEA01	11
Q_CAP_C0805-10UF,25V,10%,X6S,CH6104KEA00	CH6104KEA00	53
Q_CAP_C0805-22UF,10V,20%,X6S,CH6222MEA01	CH6222MEA01	5
Q_CAP_C0805-22UF,16V,20%,EMPTY,CH6223MEA00	CH6223MEA00	3
Q_CAP_C0805-22UF,16V,20%,X6S,CH6223MEA00	CH6223MEA00	5
Q_CAP_C0805-22UF,16V,20%,X6S,CH6223MEA01	CH6223MEA01	233
Q_CAP_C0805-22UF,4V,20%,EMPTY,CH622KMEA03	CH622KMEA03	4
Q_CAP_C0805-22UF,4V,20%,X6S,CH622KMEA03	CH622KMEA03	116
Q_CAP_C0805-47UF,4V,20%,X6S,CH647KMEA04	CH647KMEA04	12
Q_CAP_DIFFBUS_C0201-DIFF BUS_0.22UF,6.3V,20%,X6S,SA	CH4221MEE01	598
Q_CAP_DIFFBUS_C0402-DIFF BUS_0.33UF,6.3V,10%,X6S,SA	CH4331KEB01	6
Q_CRYSTAL_SMLF-32.768KHZ,EMPTY,BG632768012	BG632768012	1
Q_CRYSTAL_SMLF-32.768KHZ,IC,BG632768012	BG632768012	1
Q_FUSE_SMLF-20A/125V,IC,DKK00XFU000	DKK00XFU000	1
Q_INDUCTOR4P_14-150NH,SMLF,IND,CV+15^0TZ04	CV+15^0TZ04	38
Q_INDUCTOR_SMLF-0.22UH/33A,IND,CV+22Y0EZ00	CV+22Y0EZ00	4
Q_INDUCTOR_SMLF-1.0UH/18A,IND,CV-10I0MZ01	CV-10I0MZ01	2
Q_INDUCTOR_SMLF-1.5UH,IND,CV-15I0MZ28	CV-15I0MZ28	1
Q_INDUCTOR_SMLF-1.5UH/53A,IND,CV-15^0MZ02	CV-15^0MZ02	1
Q_INDUCTOR_SMLF-100NH/16A,IND,CV+10G0MZ04	CV+10G0MZ04	15
Q_INDUCTOR_SMLF-120NH/69A,IND,CV+12^0EZ03	CV+12^0EZ03	8
Q_INDUCTOR_SMLF-1UH,IND,CV-10U0MZ01	CV-10U0MZ01	2
Q_INDUCTOR_SMLF-2.2UH,IND,CV-2280MZ15	CV-2280MZ15	1
Q_INDUCTOR_SMLF-3.3UH/6A,IND,CV-3360MZ07	CV-3360MZ07	1
Q_INDUCTOR_SMLF-4.7UH,IND,CV-47A0MZ10	CV-47A0MZ10	1
Q_INDUCTOR_SMLF-50NH/86A,IND,CVA50^0MZ09	CVA50^0MZ09	8
Q_INDUCTOR_SMLF-90NH/155A,IND,CVA90^0KZ13	CVA90^0KZ13	4
Q_INDUCTOR_SMLF-BLM15PD121SN1D/1300MA,IND,CX5PD121A	CX5PD121000	8
Q_INDUCTOR_SMLF-BLM18PG300SN1D ,IND,TMP_QCX8PG3000A	CX8PG300001	4
Q_INDUCTOR_SMLF-BLM18SN220TN1D/8000MA,IND,CX220TN1A	CX220TN1001	6
Q_INDUCTOR_SMLF-BLM21PG221SN1D,IND,CX1PG221001	CX1PG221001	4
Q_INDUCTOR_SMLF-BLM21SN300SN1D/5A,IND,CX300SN1000	CX300SN1000	8
Q_INDUCTOR_SMLF-FCM2012KF-601T/0.5A,IND,CX601T05003	CX601T05003	5
Q_LED_SMLF-LED_BLUE,LTST-C281TBKT-5A,IC,BEBL0172Z00	BEBL0172Z00	26
Q_LED_SMLF-LED_YELLOW,LTST-C190KSKT-P,IC,BEYL0159ZA	BEYL0159Z00	4
Q_OSC4P_SMLF-50MHZ,OSC,BF650000032	BF650000032	1
Q_RES_0201LF-0,5%,1/20W,CHIP,CS00001JE10	CS00001JE10	127
Q_RES_0201LF-10K,1%,1/20W,CHIP,CS31001FE17	CS31001FE17	42
Q_RES_0201LF-1K,1%,1/20W,CHIP,CS21001FE07	CS21001FE07	88
Q_RES_0201LF-1K,1%,1/20W,EMPTY,CS21001FE07	CS21001FE07	48
Q_RES_0201LF-200,1%,1/20W,CHIP,CS12001FE12	CS12001FE12	16
Q_RES_0201LF-20K,1%,1/20W,CHIP,CS32001FE00	CS32001FE00	8
Q_RES_0201LF-22,1%,1/20W,CHIP,CS02201FE11	CS02201FE11	2
Q_RES_0201LF-33.2,1%,1/20W,CHIP,CS03321FE09	CS03321FE09	17
Q_RES_0201LF-4.7K,5%,1/20W,CHIP,CS24701JE04	CS24701JE04	78
Q_RES_0201LF-4.7K,5%,1/20W,EMPTY,CS24701JE04	CS24701JE04	94
Q_RES_0201LF-49.9,1%,1/20W,CHIP,CS04991FE06	CS04991FE06	14
Q_RES_0201LF-49.9,1%,1/20W,EMPTY,CS04991FE06	CS04991FE06	6
Q_RES_0201LF-51.1,1%,1/20W,EMPTY,CS05111FE00	CS05111FE00	16
Q_RES_0402LF-0,5%,1/16W,CHIP,CS00002JB13	CS00002JB13	874
Q_RES_0402LF-0,5%,1/16W,EMPTY,CS00002JB13	CS00002JB13	192
Q_RES_0402LF-1,1%,1/16W,CHIP,CS-1002FB04	CS-1002FB04	18
Q_RES_0402LF-1.21K,1%,1/16W,CHIP,CS21212FB05	CS21212FB05	1
Q_RES_0402LF-1.33K,1%,1/16W,CHIP,CS21332FB05	CS21332FB05	3
Q_RES_0402LF-1.5,1%,1/8W,EMPTY,CS-1504FB00	CS-1504FB00	46
Q_RES_0402LF-1.5K,1%,1/16W,EMPTY,CS21502FB07	CS21502FB07	1
Q_RES_0402LF-1.96K,1%,1/16W,CHIP,CS21962FB05	CS21962FB05	1
Q_RES_0402LF-10,1%,1/16W,CHIP,CS01002FB07	CS01002FB07	66
Q_RES_0402LF-10,1%,1/16W,EMPTY,CS01002FB07	CS01002FB07	1
Q_RES_0402LF-10.5K,1%,1/16W,CHIP,CS31052FB03	CS31052FB03	2
Q_RES_0402LF-100,1%,1/16W,CHIP,CS11002FB07	CS11002FB07	17
Q_RES_0402LF-100,1%,1/16W,EMPTY,CS11002FB07	CS11002FB07	8
Q_RES_0402LF-100K,1%,1/16W,CHIP,CS41002FB09	CS41002FB09	79
Q_RES_0402LF-100K,1%,1/16W,EMPTY,CS41002FB09	CS41002FB09	48
Q_RES_0402LF-10K,1%,1/16W,CHIP,CS31002FB08	CS31002FB08	162
Q_RES_0402LF-10K,1%,1/16W,EMPTY,CS31002FB08	CS31002FB08	61
Q_RES_0402LF-10K,5%,1/16W,CHIP,CS31002JB08	CS31002JB08	35
Q_RES_0402LF-10K,5%,1/16W,EMPTY,CS31002JB08	CS31002JB08	29
Q_RES_0402LF-10M,1%,1/16W,CHIP,CS61002FB02	CS61002FB02	9
Q_RES_0402LF-10M,1%,1/16W,EMPTY,CS61002FB02	CS61002FB02	1
Q_RES_0402LF-11.5K,1%,1/16W,CHIP,CS31152FB03	CS31152FB03	1
Q_RES_0402LF-11.5K,1%,1/16W,EMPTY,CS31152FB03	CS31152FB03	2
Q_RES_0402LF-11.8K,0.1%,1/16W,CHIP,CS31182BB06	CS31182BB06	1
Q_RES_0402LF-12.4K,1%,1/16W,CHIP,CS31242FB02	CS31242FB02	1
Q_RES_0402LF-120K,1%,1/16W,CHIP,CS41202FB05	CS41202FB05	9
Q_RES_0402LF-12K,1%,1/16W,CHIP,CS31202FB04	CS31202FB04	1
Q_RES_0402LF-13.7K,1%,1/16W,CHIP,CS31372FB03	CS31372FB03	1
Q_RES_0402LF-130,1%,1/16W,CHIP,CS11302FB03	CS11302FB03	21
Q_RES_0402LF-14.3K,1%,1/16W,CHIP,CS31432FB02	CS31432FB02	2
Q_RES_0402LF-15,1%,1/16W,CHIP,CS01502FB03	CS01502FB03	24
Q_RES_0402LF-15.4K,1%,1/16W,CHIP,CS31542FB02	CS31542FB02	4
Q_RES_0402LF-15K,0.1%,1/16W,CHIP,CS31502BB03	CS31502BB03	1
Q_RES_0402LF-15K,1%,1/16W,CHIP,CS31502FB05	CS31502FB05	7
Q_RES_0402LF-16.9K,1%,1/16W,CHIP,CS31692FB03	CS31692FB03	4
Q_RES_0402LF-160K,1%,1/16W,CHIP,CS41602FB05	CS41602FB05	4
Q_RES_0402LF-160K,1%,1/16W,EMPTY,CS41602FB05	CS41602FB05	3
Q_RES_0402LF-17.4K,1%,1/16W,CHIP,CS31742FB04	CS31742FB04	2
Q_RES_0402LF-17.8K,1%,1/16W,CHIP,CS31782FB04	CS31782FB04	3
Q_RES_0402LF-18K,1%,1/16W,CHIP,CS31802FB04	CS31802FB04	8
Q_RES_0402LF-1K,1%,1/16W,CHIP,CS21002FB06	CS21002FB06	234
Q_RES_0402LF-1K,1%,1/16W,EMPTY,CS21002FB06	CS21002FB06	184
Q_RES_0402LF-1M,1%,1/16W,CHIP,CS51002FB05	CS51002FB05	3
Q_RES_0402LF-1M,1%,1/16W,EMPTY,CS51002FB05	CS51002FB05	1
Q_RES_0402LF-2.2,1%,1/16W,CHIP,CS-2202FB01	CS-2202FB01	48
Q_RES_0402LF-2.2,5%,1/16W,CHIP,TMP_QCS-2202JB25	CS-2202JB25	4
Q_RES_0402LF-2.2K,5%,1/16W,CHIP,CS22202JB07	CS22202JB07	84
Q_RES_0402LF-2.2K,5%,1/16W,EMPTY,CS22202JB07	CS22202JB07	21
Q_RES_0402LF-2.49K,1%,1/16W,CHIP,CS22492FB05	CS22492FB05	1
Q_RES_0402LF-2.67K,1%,1/16W,CHIP,CS22672FB03	CS22672FB03	1
Q_RES_0402LF-2.8K,1%,1/16W,CHIP,CS22802FB04	CS22802FB04	1
Q_RES_0402LF-200,1%,1/16W,CHIP,CS12002FB06	CS12002FB06	7
Q_RES_0402LF-200K,1%,1/16W,CHIP,CS42002FB05	CS42002FB05	5
Q_RES_0402LF-200K,1%,1/16W,EMPTY,CS42002FB05	CS42002FB05	8
Q_RES_0402LF-20K,1%,1/16W,CHIP,CS32002FB06	CS32002FB06	7
Q_RES_0402LF-20M,1%,1/16W,CHIP,CS62002FB01	CS62002FB01	2
Q_RES_0402LF-21.5K,1%,1/16W,CHIP,CS32152FB04	CS32152FB04	1
Q_RES_0402LF-22,1%,1/16W,CHIP,CS02202FB02	CS02202FB02	19
Q_RES_0402LF-22,1%,1/16W,EMPTY,CS02202FB02	CS02202FB02	5
Q_RES_0402LF-22.1K,1%,1/16W,CHIP,CS32212FB02	CS32212FB02	1
Q_RES_0402LF-23.2K,1%,1/16W,CHIP,CS32322FB03	CS32322FB03	4
Q_RES_0402LF-24.3K,1%,1/16W,CHIP,CS32432FB03	CS32432FB03	1
Q_RES_0402LF-249,1%,1/16W,CHIP,CS12492FB02	CS12492FB02	2
Q_RES_0402LF-25.5K,1%,1/16W,CHIP,CS32552FB06	CS32552FB06	3
Q_RES_0402LF-26.7K,1%,1/16W,EMPTY,CS32672FB03	CS32672FB03	1
Q_RES_0402LF-267K,1%,1/16W,EMPTY,CS42672FB03	CS42672FB03	1
Q_RES_0402LF-27,5%,1/16W,CHIP,CS02702JB02	CS02702JB02	1
Q_RES_0402LF-27.4,1%,1/16W,CHIP,CS02742FB03	CS02742FB03	3
Q_RES_0402LF-2K,0.1%,1/16W,CHIP,CS22002BB07	CS22002BB07	10
Q_RES_0402LF-2K,1%,1/16W,CHIP,CS22002FB07	CS22002FB07	5
Q_RES_0402LF-2K,1%,1/16W,EMPTY,CS22002FB07	CS22002FB07	9
Q_RES_0402LF-2K,5%,1/16W,EMPTY,TMP_QCS22002JB29	CS22002JB29	8
Q_RES_0402LF-3.09K,1%,1/16W,CHIP,CS23092FB04	CS23092FB04	1
Q_RES_0402LF-3.9K,5%,1/16W,EMPTY,CS23902JB04	CS23902JB04	1
Q_RES_0402LF-30.1K,1%,1/16W,CHIP,CS33012FB03	CS33012FB03	3
Q_RES_0402LF-30K,1%,1/16W,CHIP,CS33002FB02	CS33002FB02	5
Q_RES_0402LF-30K,1%,1/16W,EMPTY,CS33002FB02	CS33002FB02	3
Q_RES_0402LF-31.6K,1%,1/16W,CHIP,CS33162FB02	CS33162FB02	1
Q_RES_0402LF-33,5%,1/16W,CHIP,CS03302JB10	CS03302JB10	173
Q_RES_0402LF-33,5%,1/16W,EMPTY,CS03302JB10	CS03302JB10	6
Q_RES_0402LF-33.2,1%,1/16W,CHIP,CS03322FB03	CS03322FB03	156
Q_RES_0402LF-33.2,1%,1/16W,EMPTY,CS03322FB03	CS03322FB03	3
Q_RES_0402LF-33K,1%,1/16W,CHIP,CS33302FB00	CS33302FB00	1
Q_RES_0402LF-35.7K,1%,1/16W,CHIP,CS33572FB01	CS33572FB01	4
Q_RES_0402LF-4.53K,1%,1/16W,CHIP,CS24532FB03	CS24532FB03	2
Q_RES_0402LF-4.75K,1%,1/16W,CHIP,CS24752FB03	CS24752FB03	2
Q_RES_0402LF-4.75K,1%,1/16W,EMPTY,CS24752FB03	CS24752FB03	2
Q_RES_0402LF-4.7K,1%,1/16W,CHIP,CS24702FB06	CS24702FB06	34
Q_RES_0402LF-4.7K,1%,1/16W,EMPTY,CS24702FB06	CS24702FB06	35
Q_RES_0402LF-4.7K,5%,1/16W,CHIP,CS24702JB10	CS24702JB10	115
Q_RES_0402LF-4.7K,5%,1/16W,EMPTY,CS24702JB10	CS24702JB10	81
Q_RES_0402LF-4.87K,1%,1/16W,EMPTY,CS24872FB01	CS24872FB01	2
Q_RES_0402LF-4.87K,1%,1/16W,EMPTY,CS24872FB07	CS24872FB07	2
Q_RES_0402LF-4.99K,0.1%,1/16W,CHIP,CS24992BB04	CS24992BB04	2
Q_RES_0402LF-4.99K,1%,1/16W,EMPTY,CS24992FB07	CS24992FB07	6
Q_RES_0402LF-40.2K,1%,1/16W,CHIP,CS34022FB04	CS34022FB04	6
Q_RES_0402LF-46.4K,1%,1/16W,CHIP,CS34642FB02	CS34642FB02	1
Q_RES_0402LF-470,1%,1/16W,CHIP,CS14702FB04	CS14702FB04	3
Q_RES_0402LF-47K,0.1%,1/16W,CHIP,CS34702BB05	CS34702BB05	1
Q_RES_0402LF-47K,0.1%,1/16W,EMPTY,CS34702BB05	CS34702BB05	4
Q_RES_0402LF-49.9,1%,1/16W,CHIP,CS04992FB07	CS04992FB07	75
Q_RES_0402LF-49.9,1%,1/16W,EMPTY,CS04992FB07	CS04992FB07	4
Q_RES_0402LF-5.11K,1%,1/16W,CHIP,CS25112FB04	CS25112FB04	12
Q_RES_0402LF-5.23K,1%,1/16W,CHIP,CS25232FB08	CS25232FB08	1
Q_RES_0402LF-5.36K,1%,1/16W,CHIP,CS25362FB02	CS25362FB02	2
Q_RES_0402LF-5.36K,1%,1/16W,EMPTY,CS25362FB02	CS25362FB02	2
Q_RES_0402LF-5.6,1%,1/16W,CHIP,CS-5602FB01	CS-5602FB01	46
Q_RES_0402LF-51,5%,1/16W,EMPTY,CS05102JB04	CS05102JB04	2
Q_RES_0402LF-510K,5%,1/16W,EMPTY,CS45102JB03	CS45102JB03	1
Q_RES_0402LF-54.9K,1%,1/16W,CHIP,CS35492FB03	CS35492FB03	21
Q_RES_0402LF-54.9K,1%,1/16W,EMPTY,CS35492FB03	CS35492FB03	8
Q_RES_0402LF-560,1%,1/16W,CHIP,CS15602FB03	CS15602FB03	6
Q_RES_0402LF-56K,1%,1/16W,CHIP,CS35602FB00	CS35602FB00	2
Q_RES_0402LF-6.04K,1%,1/16W,CHIP,CS26042FB04	CS26042FB04	1
Q_RES_0402LF-6.19K,1%,1/16W,CHIP,CS26192FB03	CS26192FB03	1
Q_RES_0402LF-6.8K,1%,1/16W,CHIP,CS26802FB02	CS26802FB02	4
Q_RES_0402LF-6.98K,1%,1/16W,CHIP,CS26982FB08	CS26982FB08	1
Q_RES_0402LF-60.4K,1%,1/16W,CHIP,CS36042FB04	CS36042FB04	2
Q_RES_0402LF-63.4K,1%,1/16W,CHIP,CS36342FB04	CS36342FB04	1
Q_RES_0402LF-680,1%,1/16W,CHIP,CS16802FB03	CS16802FB03	1
Q_RES_0402LF-681,1%,1/16W,CHIP,CS16812FB02	CS16812FB02	1
Q_RES_0402LF-68K,1%,1/16W,EMPTY,CS36802FB04	CS36802FB04	8
Q_RES_0402LF-7.15K,1%,1/16W,CHIP,CS27152FB03	CS27152FB03	5
Q_RES_0402LF-7.87K,1%,1/16W,CHIP,CS27872FB02	CS27872FB02	1
Q_RES_0402LF-71.5K,1%,1/16W,CHIP,CS37152FB05	CS37152FB05	3
Q_RES_0402LF-71.5K,1%,1/16W,EMPTY,CS37152FB05	CS37152FB05	4
Q_RES_0402LF-75K,0.1%,1/16W,CHIP,CS37502BB01	CS37502BB01	2
Q_RES_0402LF-8.45K,1%,1/16W,EMPTY,CS28452FB06	CS28452FB06	1
Q_RES_0402LF-8.66K,1%,1/16W,CHIP,CS28662FB02	CS28662FB02	2
Q_RES_0402LF-8.87K,1%,1/16W,EMPTY,CS28872FB01	CS28872FB01	42
Q_RES_0402LF-82K,1%,1/16W,CHIP,CS38202FB01	CS38202FB01	1
Q_RES_0402LF-84.5K,1%,1/16W,CHIP,CS38452FB05	CS38452FB05	4
Q_RES_0402LF-845,1%,1/16W,CHIP,CS18452FB01	CS18452FB01	2
Q_RES_0402LF-86.6K,1%,1/16W,CHIP,CS38662FB05	CS38662FB05	1
Q_RES_0402LF-86.6K,1%,1/16W,EMPTY,CS38662FB05	CS38662FB05	1
Q_RES_0402LF-9.09K,1%,1/16W,CHIP,CS29092FB05	CS29092FB05	2
Q_RES_0402LF-9.31K,1%,1/16W,CHIP,CS29312FB02	CS29312FB02	1
Q_RES_0402LF-9.53K,1%,1/16W,CHIP,CS29532FB06	CS29532FB06	2
Q_RES_0402LF-9.76K,1%,1/16W,CHIP,CS29762FB05	CS29762FB05	1
Q_RES_0402LF-90.9K,1%,1/16W,CHIP,CS39092FB04	CS39092FB04	1
Q_RES_0603LF-0,5%,1/4W,CHIP,CS00006J900	CS00006J900	8
Q_RES_0603LF-0,5%,1/4W,EMPTY,CS00006J900	CS00006J900	8
Q_RES_0603LF-1,1%,1/10W,CHIP,CS-1003F900	CS-1003F900	4
Q_RES_0603LF-49.9,1%,1/10W,CHIP,CS04993F909	CS04993F909	4
Q_RES_0603LF-499,1%,1/10W,CHIP,CS14993F901	CS14993F901	2
Q_RES_1206LF-243,1%,1/4W,CHIP,CS12436F201	CS12436F201	4
Q_RES_2512LF-0.002,1%,2W,CHIP,CS+002AFR06	CS+002AFR06	8
Q_RES_2512LF-10,1%,2W,EMPTY,CS0100AFR00	CS0100AFR00	2
Q_RES_4P_12-0.001,1%,3W,SMLF,CHIP,SP_CS+001DFR10	CS+001DFR10	2
Q_SHORT_SM-EMPTY,SHORT16	SHORT16	4
Q_SP_RES4P-0.0003,1%,4W,SMLF,CHIP,SP_CS0000FFT09	CS0000FFT09	4
Q_SP_RES4P-0.003,1%,2W,SMLF,CHIP,SP_CS+003AFR00_1	CS+003AFR00	1
Q_XTAL_4P_13BI_24GND-12MHZ,SMLF,MISC,BG6120000B0	BG6120000B0	1
Q_XTAL_4P_13BI_24GND-24MHZ,SMLF,MISC,BG624000101	BG624000101	1
Q_XTAL_4P_13BI_24GND-25MHZ,SMLF,MISC,BG6250000L4	BG6250000L4	1
Q_XTAL_4P_13BI_24GND-26MHZ,SMLF,MISC,BG626000049	BG626000049	1
Q_XTAL_4P_13BI_24GND-48MHZ,SMLF,MISC,BG648000076	BG648000076	2
RAA229620GNPHA0-RAA229620GNP#HA0,SMLF,IC,ARF0TGP40A	ARF0TGP4002	4
RAA229621GNPHA0-RAA229621GNP#HA0,SMLF,IC,ARF0TGP40A	ARF0TGP4003	2
RS31312R-RS31312R,SMLF,IC,AL031312000	AL031312000	4
RT9818C44GV-RT9818C-44GV,SMLF,IC,AL009818001	AL009818001	1
SCHOTTKY_12-B0530WS7F,SMLF,EMPTY,BC000530Z41	BC000530Z41	4
SCHOTTKY_AC-B340A-13-F,SMLF,IC,BC000340Z30	BC000340Z30	7
SCHOTTKY_DUAL_12A_3C-BAT54CW,SMLF,EMPTY,BCBAT54CZ13	BCBAT54CZ13	2
SCHOTTKY_DUAL_12A_3C-BAT54CW,SMLF,IC,BCBAT54CZ13	BCBAT54CZ13	1
SCONN168_ME1016810202011-SCONN168_ME1016810202011,A	DFHSG8FR011	3
SCONN20_HSU2101L00007H-SCONN20_HSU2101-L0000-7H,SMA	DFHD20MS153	1
SCONN21_9193031121LF-SCONN21_91930-31121LF,SMLF,IOA	DFHS21FS003	1
SCONN288_DDR506112002KQ-SCONN288_DDR506112002KQ,SMA	DFHST8FS479	24
SCONN56_123276793-SCONN56_1-2327679-3,SMLF,IO,DFHSA	DFHS56FS022	1
SCONN75K_APCI0155P004A-SCONN75K_APCI0155-P004A,SMLA	DFHS75FR313	1
SCONN8_G802M0083150RD3HR-SCONN8_G802M0083150RD3HR,A	DFHD08MS385	4
SN74AUC2G66DCTR-SN74AUC2G66DCTR,SMLF,IC,AL2G0066C00	AL2G0066C00	4
SN74AVC2T245RSWR-SN74AVC2T245RSWR,SMLF,IC,AL02T245A	AL02T245000	3
SN74AVC4T774PWR-SN74AVC4T774PWR,SMLF,IC,AL04T774K00	AL04T774K00	6
SN74LVC1G07DBVR_SMLF-SN74LVC1G07DBVR,EMPTY,AL1G000A	AL1G0007024	1
SN74LVC1G07DBVR_SMLF-SN74LVC1G07DBVR,IC,AL1G0007024	AL1G0007024	10
SN74LVC1G11DCKR-SN74LVC1G11DCKR,SMLF,IC,ALLVC1G1000	ALLVC1G1000	1
SN74LVC2G07DCKR_SMLF-SN74LVC2G07DCKR,IC,AL002G07006	AL002G07006	3
SS15P3SM386A-SS15P3S-M3/86A,SMLF,IC,BC015P3SZ00	BC015P3SZ00	2
SW20S_DHNF10FQTR-SW20S_DHNF-10F-Q-T/R,SMLF,MECH,DHA	DHD00010F01	1
TCA9548APWR-TCA9548APWR,SMLF,IC,AL009548K02	AL009548K02	4
TDR_3P_TH2-EMPTY,N_A	N_A	16
TPS71715DCKR-TPS71715DCKR,SMLF,EMPTY,AL071715001	AL071715001	1
TP_TDR_4P_FTS_TH-TP_TDR_4P_DIP,EMPTY,TP15	N_A	44
TP_TP-NA,TP26	TP26	2
TP_TP-NA,TP30	TP30	18
TUSB211IRWBR-TUSB211IRWBR,SMLF,EMPTY,AL000211007	AL000211007	1
TUSB8042AIRGCR-TUSB8042AIRGCR,SMLF,IC,AL008042000	AL008042000	1
ZENER_AC-5.0SMDJ14A,SMLF,IC,BC0MDJ14000	BC0MDJ14000	2

Total                                    8303
